(kicad_pcb
	(version 20260206)
	(generator "pcbnew")
	(generator_version "10.0")
	(general
		(thickness 1.6)
		(legacy_teardrops no)
	)
	(paper "A4")
	(title_block
		(title "03242023_DA0F0TMBIJ0_F0T_Motherboard_J_brd_V01_OCP.brd")
		(comment 1 "Grand Teton / footprints 4378-4383 of 6105")
	)
	(layers
		(0 "F.Cu" signal "TOP")
		(4 "In1.Cu" signal "GND")
		(6 "In2.Cu" signal "IN1")
		(8 "In3.Cu" signal "GND1")
		(10 "In4.Cu" signal "IN2")
		(12 "In5.Cu" signal "GND2")
		(14 "In6.Cu" signal "IN3")
		(16 "In7.Cu" signal "GND3")
		(18 "In8.Cu" signal "VCC")
		(20 "In9.Cu" signal "VCC1")
		(22 "In10.Cu" signal "GND4")
		(24 "In11.Cu" signal "IN4")
		(26 "In12.Cu" signal "GND5")
		(28 "In13.Cu" signal "IN5")
		(30 "In14.Cu" signal "GND6")
		(32 "In15.Cu" signal "IN6")
		(34 "In16.Cu" signal "GND7")
		(2 "B.Cu" signal "BOTTOM")
		(9 "F.Adhes" user "F.Adhesive")
		(11 "B.Adhes" user "B.Adhesive")
		(13 "F.Paste" user "Package Geometry/Pastemask Top")
		(15 "B.Paste" user "Package Geometry/Pastemask Bottom")
		(5 "F.SilkS" user "Ref Des/Silkscreen Top")
		(7 "B.SilkS" user "Ref Des/Silkscreen Bottom")
		(1 "F.Mask" user "Board Geometry/Soldermask Top")
		(3 "B.Mask" user "Board Geometry/Soldermask Bottom")
		(17 "Dwgs.User" user "User.Drawings")
		(19 "Cmts.User" user "User.Comments")
		(21 "Eco1.User" user "User.Eco1")
		(23 "Eco2.User" user "User.Eco2")
		(25 "Edge.Cuts" user "Board Geometry/Outline")
		(27 "Margin" user)
		(31 "F.CrtYd" user "Package Geometry/Place Bound Top")
		(29 "B.CrtYd" user "Package Geometry/Place Bound Bottom")
		(35 "F.Fab" user "Ref Des/Assembly Top")
		(33 "B.Fab" user "Ref Des/Assembly Bottom")
	)
	(footprint ""
		(layer "B.Cu")
		(at 159.766508 -41.805098 -90)
		(property "Reference" "C2313"
			(at 0 0 90)
			(layer "B.SilkS")
			(hide yes)
			(effects
				(font
					(size 1.27 1.27)
				)
				(justify mirror)
			)
		)
		(property "Value" ""
			(at 0 0 90)
			(layer "B.Fab")
			(effects
				(font
					(size 1.27 1.27)
				)
				(justify mirror)
			)
		)
		(duplicate_pad_numbers_are_jumpers no)
		(fp_line
			(start -0.7874 0.4064)
			(end 0.7874 0.4064)
			(stroke
				(width 0.1524)
				(type default)
			)
			(layer "B.SilkS")
		)
		(fp_line
			(start 0.7874 0.4064)
			(end 0.7874 -0.4064)
			(stroke
				(width 0.1524)
				(type default)
			)
			(layer "B.SilkS")
		)
		(fp_line
			(start -0.7874 -0.4064)
			(end -0.7874 0.4064)
			(stroke
				(width 0.1524)
				(type default)
			)
			(layer "B.SilkS")
		)
		(fp_line
			(start 0.7874 -0.4064)
			(end -0.7874 -0.4064)
			(stroke
				(width 0.1524)
				(type default)
			)
			(layer "B.SilkS")
		)
		(fp_line
			(start -0.67945 0.3048)
			(end -0.120396 0.3048)
			(stroke
				(width 0.1)
				(type default)
			)
			(layer "B.Fab")
		)
		(fp_line
			(start -0.120396 0.3048)
			(end -0.120396 0.2794)
			(stroke
				(width 0.1)
				(type default)
			)
			(layer "B.Fab")
		)
		(fp_line
			(start 0.12065 0.3048)
			(end 0.67945 0.3048)
			(stroke
				(width 0.1)
				(type default)
			)
			(layer "B.Fab")
		)
		(fp_line
			(start 0.67945 0.3048)
			(end 0.67945 -0.305054)
			(stroke
				(width 0.1)
				(type default)
			)
			(layer "B.Fab")
		)
		(fp_line
			(start -0.120396 0.2794)
			(end 0.12065 0.2794)
			(stroke
				(width 0.1)
				(type default)
			)
			(layer "B.Fab")
		)
		(fp_line
			(start 0.12065 0.2794)
			(end 0.12065 0.3048)
			(stroke
				(width 0.1)
				(type default)
			)
			(layer "B.Fab")
		)
		(fp_line
			(start -0.12065 -0.2794)
			(end -0.12065 -0.3048)
			(stroke
				(width 0.1)
				(type default)
			)
			(layer "B.Fab")
		)
		(fp_line
			(start 0.12065 -0.2794)
			(end -0.12065 -0.2794)
			(stroke
				(width 0.1)
				(type default)
			)
			(layer "B.Fab")
		)
		(fp_line
			(start -0.67945 -0.3048)
			(end -0.67945 0.3048)
			(stroke
				(width 0.1)
				(type default)
			)
			(layer "B.Fab")
		)
		(fp_line
			(start -0.12065 -0.3048)
			(end -0.67945 -0.3048)
			(stroke
				(width 0.1)
				(type default)
			)
			(layer "B.Fab")
		)
		(fp_line
			(start 0.12065 -0.305054)
			(end 0.12065 -0.2794)
			(stroke
				(width 0.1)
				(type default)
			)
			(layer "B.Fab")
		)
		(fp_line
			(start 0.67945 -0.305054)
			(end 0.12065 -0.305054)
			(stroke
				(width 0.1)
				(type default)
			)
			(layer "B.Fab")
		)
		(pad "1" smd circle
			(at 0.40005 0 90)
			(size 0 0)
			(layers "B.Cu" "B.Mask" "B.Paste")
			(net "P3V3_AUX_USB_HUB_2")
		)
		(pad "2" smd circle
			(at -0.40005 0 90)
			(size 0 0)
			(layers "B.Cu" "B.Mask" "B.Paste")
			(net "GND")
		)
	)
	(footprint ""
		(layer "B.Cu")
		(at 378.099574 8.003794)
		(property "Reference" "J116"
			(at 4.524756 1.521206 270)
			(unlocked yes)
			(layer "B.SilkS")
			(effects
				(font
					(size 0.7874 0.5842)
					(thickness 0.1524)
				)
				(justify left mirror)
			)
		)
		(property "Value" ""
			(at 0 0 0)
			(layer "B.Fab")
			(effects
				(font
					(size 1.27 1.27)
				)
				(justify mirror)
			)
		)
		(duplicate_pad_numbers_are_jumpers no)
		(fp_line
			(start -1.2192 -2.1082)
			(end -1.2192 2.1082)
			(stroke
				(width 0.1524)
				(type default)
			)
			(layer "B.SilkS")
		)
		(fp_line
			(start -1.2192 2.1082)
			(end 1.2192 2.1082)
			(stroke
				(width 0.1524)
				(type default)
			)
			(layer "B.SilkS")
		)
		(fp_line
			(start 1.2192 -2.1082)
			(end -1.2192 -2.1082)
			(stroke
				(width 0.1524)
				(type default)
			)
			(layer "B.SilkS")
		)
		(fp_line
			(start 1.2192 2.1082)
			(end 1.2192 -2.1082)
			(stroke
				(width 0.1524)
				(type default)
			)
			(layer "B.SilkS")
		)
		(pad "" np_thru_hole circle
			(at -3.4671 -1.27 270)
			(size 1.0414 1.0414)
			(drill 1.0414)
			(layers "*.Cu" "*.Mask")
			(clearance 0.381)
			(thermal_gap 0.381)
		)
		(pad "" np_thru_hole circle
			(at -3.4671 1.27 270)
			(size 1.0414 1.0414)
			(drill 1.0414)
			(layers "*.Cu" "*.Mask")
			(clearance 0.381)
			(thermal_gap 0.381)
		)
		(pad "" np_thru_hole circle
			(at 2.8829 -1.27 270)
			(size 1.0414 1.0414)
			(drill 1.0414)
			(layers "*.Cu" "*.Mask")
			(clearance 0.381)
			(thermal_gap 0.381)
		)
		(pad "" np_thru_hole circle
			(at 2.8829 1.27 270)
			(size 1.0414 1.0414)
			(drill 1.0414)
			(layers "*.Cu" "*.Mask")
			(clearance 0.381)
			(thermal_gap 0.381)
		)
		(pad "1" smd rect
			(at -0.8255 -0.249936 270)
			(size 0.3048 0.508)
			(layers "B.Cu" "B.Mask" "B.Paste")
			(net "DELTA_L_85_5INCH_IN5_DN")
		)
		(pad "2" smd rect
			(at -0.8255 0.249936 270)
			(size 0.3048 0.508)
			(layers "B.Cu" "B.Mask" "B.Paste")
			(net "DELTA_L_85_5INCH_IN5_DP")
		)
		(pad "3" smd circle
			(at 0 0 180)
			(size 0 0)
			(layers "B.Cu" "B.Mask" "B.Paste")
			(net "DELTA_L_GND_1")
		)
		(zone
			(layers "F.Cu" "B.Cu" "In1.Cu" "In2.Cu" "In3.Cu" "In4.Cu" "In5.Cu" "In6.Cu"
				"In7.Cu" "In8.Cu" "In9.Cu" "In10.Cu" "In11.Cu" "In12.Cu" "In13.Cu" "In14.Cu"
				"In15.Cu" "In16.Cu"
			)
			(hatch none 0.5)
			(connect_pads
				(clearance 0)
			)
			(min_thickness 0.25)
			(keepout
				(tracks not_allowed)
				(vias allowed)
				(pads allowed)
				(copperpour not_allowed)
				(footprints allowed)
			)
			(placement
				(enabled no)
				(sheetname "")
			)
			(fill
				(thermal_gap 0.5)
				(thermal_bridge_width 0.5)
				(island_removal_mode 0)
			)
			(polygon
				(pts
					(arc
						(start 375.559574 6.733794)
						(mid 373.705374 6.733794)
						(end 375.559574 6.733794)
					)
				)
			)
		)
		(zone
			(layers "F.Cu" "B.Cu" "In1.Cu" "In2.Cu" "In3.Cu" "In4.Cu" "In5.Cu" "In6.Cu"
				"In7.Cu" "In8.Cu" "In9.Cu" "In10.Cu" "In11.Cu" "In12.Cu" "In13.Cu" "In14.Cu"
				"In15.Cu" "In16.Cu"
			)
			(hatch none 0.5)
			(connect_pads
				(clearance 0)
			)
			(min_thickness 0.25)
			(keepout
				(tracks not_allowed)
				(vias allowed)
				(pads allowed)
				(copperpour not_allowed)
				(footprints allowed)
			)
			(placement
				(enabled no)
				(sheetname "")
			)
			(fill
				(thermal_gap 0.5)
				(thermal_bridge_width 0.5)
				(island_removal_mode 0)
			)
			(polygon
				(pts
					(arc
						(start 375.559574 9.273794)
						(mid 373.705374 9.273794)
						(end 375.559574 9.273794)
					)
				)
			)
		)
		(zone
			(layers "F.Cu" "B.Cu" "In1.Cu" "In2.Cu" "In3.Cu" "In4.Cu" "In5.Cu" "In6.Cu"
				"In7.Cu" "In8.Cu" "In9.Cu" "In10.Cu" "In11.Cu" "In12.Cu" "In13.Cu" "In14.Cu"
				"In15.Cu" "In16.Cu"
			)
			(hatch none 0.5)
			(connect_pads
				(clearance 0)
			)
			(min_thickness 0.25)
			(keepout
				(tracks not_allowed)
				(vias allowed)
				(pads allowed)
				(copperpour not_allowed)
				(footprints allowed)
			)
			(placement
				(enabled no)
				(sheetname "")
			)
			(fill
				(thermal_gap 0.5)
				(thermal_bridge_width 0.5)
				(island_removal_mode 0)
			)
			(polygon
				(pts
					(arc
						(start 381.909574 6.733794)
						(mid 380.055374 6.733794)
						(end 381.909574 6.733794)
					)
				)
			)
		)
		(zone
			(layers "F.Cu" "B.Cu" "In1.Cu" "In2.Cu" "In3.Cu" "In4.Cu" "In5.Cu" "In6.Cu"
				"In7.Cu" "In8.Cu" "In9.Cu" "In10.Cu" "In11.Cu" "In12.Cu" "In13.Cu" "In14.Cu"
				"In15.Cu" "In16.Cu"
			)
			(hatch none 0.5)
			(connect_pads
				(clearance 0)
			)
			(min_thickness 0.25)
			(keepout
				(tracks not_allowed)
				(vias allowed)
				(pads allowed)
				(copperpour not_allowed)
				(footprints allowed)
			)
			(placement
				(enabled no)
				(sheetname "")
			)
			(fill
				(thermal_gap 0.5)
				(thermal_bridge_width 0.5)
				(island_removal_mode 0)
			)
			(polygon
				(pts
					(arc
						(start 381.909574 9.273794)
						(mid 380.055374 9.273794)
						(end 381.909574 9.273794)
					)
				)
			)
		)
		(zone
			(layer "B.Cu")
			(hatch none 0.5)
			(connect_pads
				(clearance 0)
			)
			(min_thickness 0.25)
			(keepout
				(tracks not_allowed)
				(vias allowed)
				(pads allowed)
				(copperpour not_allowed)
				(footprints allowed)
			)
			(placement
				(enabled no)
				(sheetname "")
			)
			(fill
				(thermal_gap 0.5)
				(thermal_bridge_width 0.5)
				(island_removal_mode 0)
			)
			(polygon
				(pts
					(xy 376.981974 7.455154) (xy 376.981974 7.550658) (xy 377.578874 7.550658) (xy 377.578874 7.957058)
					(xy 376.981974 7.957058) (xy 376.981974 8.05053) (xy 377.578874 8.05053) (xy 377.578874 8.45693)
					(xy 376.981974 8.45693) (xy 376.981974 8.552434) (xy 377.680474 8.552434) (xy 377.680474 7.455154)
				)
			)
		)
	)
	(footprint ""
		(layer "B.Cu")
		(at 231.288336 -125.377194 180)
		(property "Reference" "R1543"
			(at 0 0 0)
			(layer "B.SilkS")
			(hide yes)
			(effects
				(font
					(size 1.27 1.27)
				)
				(justify mirror)
			)
		)
		(property "Value" ""
			(at 0 0 0)
			(layer "B.Fab")
			(effects
				(font
					(size 1.27 1.27)
				)
				(justify mirror)
			)
		)
		(duplicate_pad_numbers_are_jumpers no)
		(fp_line
			(start 0.7874 0.4064)
			(end 0.7874 -0.4064)
			(stroke
				(width 0.1524)
				(type default)
			)
			(layer "B.SilkS")
		)
		(fp_line
			(start 0.7874 -0.4064)
			(end -0.7874 -0.4064)
			(stroke
				(width 0.1524)
				(type default)
			)
			(layer "B.SilkS")
		)
		(fp_line
			(start -0.7874 0.4064)
			(end 0.7874 0.4064)
			(stroke
				(width 0.1524)
				(type default)
			)
			(layer "B.SilkS")
		)
		(fp_line
			(start -0.7874 -0.4064)
			(end -0.7874 0.4064)
			(stroke
				(width 0.1524)
				(type default)
			)
			(layer "B.SilkS")
		)
		(fp_line
			(start 0.67945 0.3048)
			(end 0.67945 -0.305054)
			(stroke
				(width 0.1)
				(type default)
			)
			(layer "B.Fab")
		)
		(fp_line
			(start 0.67945 -0.305054)
			(end 0.12065 -0.305054)
			(stroke
				(width 0.1)
				(type default)
			)
			(layer "B.Fab")
		)
		(fp_line
			(start 0.12065 0.3048)
			(end 0.67945 0.3048)
			(stroke
				(width 0.1)
				(type default)
			)
			(layer "B.Fab")
		)
		(fp_line
			(start 0.12065 0.2794)
			(end 0.12065 0.3048)
			(stroke
				(width 0.1)
				(type default)
			)
			(layer "B.Fab")
		)
		(fp_line
			(start 0.12065 -0.2794)
			(end -0.12065 -0.2794)
			(stroke
				(width 0.1)
				(type default)
			)
			(layer "B.Fab")
		)
		(fp_line
			(start 0.12065 -0.305054)
			(end 0.12065 -0.2794)
			(stroke
				(width 0.1)
				(type default)
			)
			(layer "B.Fab")
		)
		(fp_line
			(start -0.120396 0.3048)
			(end -0.120396 0.2794)
			(stroke
				(width 0.1)
				(type default)
			)
			(layer "B.Fab")
		)
		(fp_line
			(start -0.120396 0.2794)
			(end 0.12065 0.2794)
			(stroke
				(width 0.1)
				(type default)
			)
			(layer "B.Fab")
		)
		(fp_line
			(start -0.12065 -0.2794)
			(end -0.12065 -0.3048)
			(stroke
				(width 0.1)
				(type default)
			)
			(layer "B.Fab")
		)
		(fp_line
			(start -0.12065 -0.3048)
			(end -0.67945 -0.3048)
			(stroke
				(width 0.1)
				(type default)
			)
			(layer "B.Fab")
		)
		(fp_line
			(start -0.67945 0.3048)
			(end -0.120396 0.3048)
			(stroke
				(width 0.1)
				(type default)
			)
			(layer "B.Fab")
		)
		(fp_line
			(start -0.67945 -0.3048)
			(end -0.67945 0.3048)
			(stroke
				(width 0.1)
				(type default)
			)
			(layer "B.Fab")
		)
		(pad "1" smd circle
			(at 0.40005 0)
			(size 0 0)
			(layers "B.Cu" "B.Mask" "B.Paste")
			(net "OCP_SFF_CLK_OE_N")
		)
		(pad "2" smd circle
			(at -0.40005 0)
			(size 0 0)
			(layers "B.Cu" "B.Mask" "B.Paste")
			(net "FM_DB2000_9_OE_N")
		)
	)
	(footprint ""
		(layer "B.Cu")
		(at 111.621316 -360.847386)
		(property "Reference" "PR313"
			(at 0 0 0)
			(layer "B.SilkS")
			(hide yes)
			(effects
				(font
					(size 1.27 1.27)
				)
				(justify mirror)
			)
		)
		(property "Value" ""
			(at 0 0 0)
			(layer "B.Fab")
			(effects
				(font
					(size 1.27 1.27)
				)
				(justify mirror)
			)
		)
		(duplicate_pad_numbers_are_jumpers no)
		(fp_line
			(start -0.7874 -0.4064)
			(end -0.7874 0.4064)
			(stroke
				(width 0.1524)
				(type default)
			)
			(layer "B.SilkS")
		)
		(fp_line
			(start -0.7874 0.4064)
			(end 0.7874 0.4064)
			(stroke
				(width 0.1524)
				(type default)
			)
			(layer "B.SilkS")
		)
		(fp_line
			(start 0.7874 -0.4064)
			(end -0.7874 -0.4064)
			(stroke
				(width 0.1524)
				(type default)
			)
			(layer "B.SilkS")
		)
		(fp_line
			(start 0.7874 0.4064)
			(end 0.7874 -0.4064)
			(stroke
				(width 0.1524)
				(type default)
			)
			(layer "B.SilkS")
		)
		(fp_line
			(start -0.67945 -0.3048)
			(end -0.67945 0.3048)
			(stroke
				(width 0.1)
				(type default)
			)
			(layer "B.Fab")
		)
		(fp_line
			(start -0.67945 0.3048)
			(end -0.120396 0.3048)
			(stroke
				(width 0.1)
				(type default)
			)
			(layer "B.Fab")
		)
		(fp_line
			(start -0.12065 -0.3048)
			(end -0.67945 -0.3048)
			(stroke
				(width 0.1)
				(type default)
			)
			(layer "B.Fab")
		)
		(fp_line
			(start -0.12065 -0.2794)
			(end -0.12065 -0.3048)
			(stroke
				(width 0.1)
				(type default)
			)
			(layer "B.Fab")
		)
		(fp_line
			(start -0.120396 0.2794)
			(end 0.12065 0.2794)
			(stroke
				(width 0.1)
				(type default)
			)
			(layer "B.Fab")
		)
		(fp_line
			(start -0.120396 0.3048)
			(end -0.120396 0.2794)
			(stroke
				(width 0.1)
				(type default)
			)
			(layer "B.Fab")
		)
		(fp_line
			(start 0.12065 -0.305054)
			(end 0.12065 -0.2794)
			(stroke
				(width 0.1)
				(type default)
			)
			(layer "B.Fab")
		)
		(fp_line
			(start 0.12065 -0.2794)
			(end -0.12065 -0.2794)
			(stroke
				(width 0.1)
				(type default)
			)
			(layer "B.Fab")
		)
		(fp_line
			(start 0.12065 0.2794)
			(end 0.12065 0.3048)
			(stroke
				(width 0.1)
				(type default)
			)
			(layer "B.Fab")
		)
		(fp_line
			(start 0.12065 0.3048)
			(end 0.67945 0.3048)
			(stroke
				(width 0.1)
				(type default)
			)
			(layer "B.Fab")
		)
		(fp_line
			(start 0.67945 -0.305054)
			(end 0.12065 -0.305054)
			(stroke
				(width 0.1)
				(type default)
			)
			(layer "B.Fab")
		)
		(fp_line
			(start 0.67945 0.3048)
			(end 0.67945 -0.305054)
			(stroke
				(width 0.1)
				(type default)
			)
			(layer "B.Fab")
		)
		(pad "1" smd circle
			(at 0.40005 0 180)
			(size 0 0)
			(layers "B.Cu" "B.Mask" "B.Paste")
			(net "PVCCIN_CPU1_VIN_CSNIN")
		)
		(pad "2" smd circle
			(at -0.40005 0 180)
			(size 0 0)
			(layers "B.Cu" "B.Mask" "B.Paste")
			(net "GND")
		)
	)
	(footprint ""
		(layer "B.Cu")
		(at 158.707074 -41.816528 -90)
		(property "Reference" "C2314"
			(at 0 0 90)
			(layer "B.SilkS")
			(hide yes)
			(effects
				(font
					(size 1.27 1.27)
				)
				(justify mirror)
			)
		)
		(property "Value" ""
			(at 0 0 90)
			(layer "B.Fab")
			(effects
				(font
					(size 1.27 1.27)
				)
				(justify mirror)
			)
		)
		(duplicate_pad_numbers_are_jumpers no)
		(fp_line
			(start -0.7874 0.4064)
			(end 0.7874 0.4064)
			(stroke
				(width 0.1524)
				(type default)
			)
			(layer "B.SilkS")
		)
		(fp_line
			(start 0.7874 0.4064)
			(end 0.7874 -0.4064)
			(stroke
				(width 0.1524)
				(type default)
			)
			(layer "B.SilkS")
		)
		(fp_line
			(start -0.7874 -0.4064)
			(end -0.7874 0.4064)
			(stroke
				(width 0.1524)
				(type default)
			)
			(layer "B.SilkS")
		)
		(fp_line
			(start 0.7874 -0.4064)
			(end -0.7874 -0.4064)
			(stroke
				(width 0.1524)
				(type default)
			)
			(layer "B.SilkS")
		)
		(fp_line
			(start -0.67945 0.3048)
			(end -0.120396 0.3048)
			(stroke
				(width 0.1)
				(type default)
			)
			(layer "B.Fab")
		)
		(fp_line
			(start -0.120396 0.3048)
			(end -0.120396 0.2794)
			(stroke
				(width 0.1)
				(type default)
			)
			(layer "B.Fab")
		)
		(fp_line
			(start 0.12065 0.3048)
			(end 0.67945 0.3048)
			(stroke
				(width 0.1)
				(type default)
			)
			(layer "B.Fab")
		)
		(fp_line
			(start 0.67945 0.3048)
			(end 0.67945 -0.305054)
			(stroke
				(width 0.1)
				(type default)
			)
			(layer "B.Fab")
		)
		(fp_line
			(start -0.120396 0.2794)
			(end 0.12065 0.2794)
			(stroke
				(width 0.1)
				(type default)
			)
			(layer "B.Fab")
		)
		(fp_line
			(start 0.12065 0.2794)
			(end 0.12065 0.3048)
			(stroke
				(width 0.1)
				(type default)
			)
			(layer "B.Fab")
		)
		(fp_line
			(start -0.12065 -0.2794)
			(end -0.12065 -0.3048)
			(stroke
				(width 0.1)
				(type default)
			)
			(layer "B.Fab")
		)
		(fp_line
			(start 0.12065 -0.2794)
			(end -0.12065 -0.2794)
			(stroke
				(width 0.1)
				(type default)
			)
			(layer "B.Fab")
		)
		(fp_line
			(start -0.67945 -0.3048)
			(end -0.67945 0.3048)
			(stroke
				(width 0.1)
				(type default)
			)
			(layer "B.Fab")
		)
		(fp_line
			(start -0.12065 -0.3048)
			(end -0.67945 -0.3048)
			(stroke
				(width 0.1)
				(type default)
			)
			(layer "B.Fab")
		)
		(fp_line
			(start 0.12065 -0.305054)
			(end 0.12065 -0.2794)
			(stroke
				(width 0.1)
				(type default)
			)
			(layer "B.Fab")
		)
		(fp_line
			(start 0.67945 -0.305054)
			(end 0.12065 -0.305054)
			(stroke
				(width 0.1)
				(type default)
			)
			(layer "B.Fab")
		)
		(pad "1" smd circle
			(at 0.40005 0 90)
			(size 0 0)
			(layers "B.Cu" "B.Mask" "B.Paste")
			(net "P3V3_AUX_USB_HUB_2")
		)
		(pad "2" smd circle
			(at -0.40005 0 90)
			(size 0 0)
			(layers "B.Cu" "B.Mask" "B.Paste")
			(net "GND")
		)
	)
	(footprint ""
		(layer "B.Cu")
		(at 96.8248 -128.91516)
		(property "Reference" "ME3"
			(at 9.652 -9.540748 0)
			(unlocked yes)
			(layer "B.SilkS")
			(effects
				(font
					(size 0.7874 0.5842)
					(thickness 0.1524)
				)
				(justify left mirror)
			)
		)
		(property "Value" ""
			(at 0 0 0)
			(layer "B.Fab")
			(effects
				(font
					(size 1.27 1.27)
				)
				(justify mirror)
			)
		)
		(duplicate_pad_numbers_are_jumpers no)
		(zone
			(layer "B.Cu")
			(hatch none 0.5)
			(connect_pads
				(clearance 0)
			)
			(min_thickness 0.25)
			(keepout
				(tracks allowed)
				(vias allowed)
				(pads allowed)
				(copperpour allowed)
				(footprints not_allowed)
			)
			(placement
				(enabled no)
				(sheetname "")
			)
			(fill
				(thermal_gap 0.5)
				(thermal_bridge_width 0.5)
				(island_removal_mode 0)
			)
			(polygon
				(pts
					(arc
						(start 106.82478 -128.91516)
						(mid 86.82482 -128.91516)
						(end 106.82478 -128.91516)
					)
				)
			)
		)
	)
)
